(kicad_pcb
	(version 20260206)
	(generator "pcbnew")
	(generator_version "10.0")
	(general
		(thickness 1.6)
		(legacy_teardrops no)
	)
	(paper "A4")
	(title_block
		(title "fcb — 12433-1M.1206WZS1330.brd")
		(comment 1 "Open Vault / Knox (Wiwynn) / footprints 209-215 of 495")
	)
	(layers
		(0 "F.Cu" signal "TOP")
		(4 "In1.Cu" signal "L2GND")
		(6 "In2.Cu" signal "L3VCC")
		(2 "B.Cu" signal "BOTTOM")
		(9 "F.Adhes" user "F.Adhesive")
		(11 "B.Adhes" user "B.Adhesive")
		(13 "F.Paste" user "Package Geometry/Pastemask Top")
		(15 "B.Paste" user "Package Geometry/Pastemask Bottom")
		(5 "F.SilkS" user "Ref Des/Silkscreen Top")
		(7 "B.SilkS" user "Ref Des/Silkscreen Bottom")
		(1 "F.Mask" user "Board Geometry/Soldermask Top")
		(3 "B.Mask" user "Board Geometry/Soldermask Bottom")
		(17 "Dwgs.User" user "User.Drawings")
		(19 "Cmts.User" user "User.Comments")
		(21 "Eco1.User" user "User.Eco1")
		(23 "Eco2.User" user "User.Eco2")
		(25 "Edge.Cuts" user "Board Geometry/Outline")
		(27 "Margin" user)
		(31 "F.CrtYd" user "Package Geometry/Place Bound Top")
		(29 "B.CrtYd" user "Package Geometry/Place Bound Bottom")
		(35 "F.Fab" user "Ref Des/Assembly Top")
		(33 "B.Fab" user "Ref Des/Assembly Bottom")
	)
	(footprint ""
		(layer "F.Cu")
		(at 25.5016 -139.5984 -90)
		(property "Reference" "PR99"
			(at 0 0 270)
			(layer "F.SilkS")
			(hide yes)
			(effects
				(font
					(size 1.27 1.27)
				)
			)
		)
		(property "Value" "100R2F-L1-GP-U"
			(at 0.064008 -3.993896 270)
			(unlocked yes)
			(layer "F.Fab")
			(hide yes)
			(effects
				(font
					(size 1.016 1.016)
					(thickness 0.1524)
				)
			)
		)
		(property "Device Type" "R402H14"
			(at 0.064008 -5.517896 270)
			(unlocked yes)
			(layer "F.Fab")
			(hide yes)
			(effects
				(font
					(size 1.016 1.016)
					(thickness 0.1524)
				)
			)
		)
		(duplicate_pad_numbers_are_jumpers no)
		(fp_line
			(start -0.508 -0.9398)
			(end -0.508 0.9398)
			(stroke
				(width 0.1524)
				(type default)
			)
			(layer "F.SilkS")
		)
		(fp_line
			(start 0.508 -0.9398)
			(end -0.508 -0.9398)
			(stroke
				(width 0.1524)
				(type default)
			)
			(layer "F.SilkS")
		)
		(fp_rect
			(start -0.508 0.9398)
			(end 0.508 -0.9398)
			(stroke
				(width 0)
				(type default)
			)
			(fill no)
			(layer "F.CrtYd")
		)
		(fp_rect
			(start -0.508 0.9398)
			(end 0.508 -0.9398)
			(stroke
				(width 0)
				(type default)
			)
			(fill no)
			(layer "F.Fab")
		)
		(pad "1" smd custom
			(at 0 -0.4445 270)
			(size 0.1397 0.1397)
			(layers "F.Cu" "F.Mask" "F.Paste")
			(net "P12VU_2490_GATE")
			(options
				(clearance outline)
				(anchor circle)
			)
			(primitives
				(gr_poly
					(pts
						(arc
							(start -0.1778 -0.2794)
							(mid -0.249642 -0.249642)
							(end -0.2794 -0.1778)
						)
						(arc
							(start -0.2794 0.1778)
							(mid -0.249642 0.249642)
							(end -0.1778 0.2794)
						)
						(arc
							(start 0.1778 0.2794)
							(mid 0.249642 0.249642)
							(end 0.2794 0.1778)
						)
						(arc
							(start 0.2794 -0.1778)
							(mid 0.249642 -0.249642)
							(end 0.1778 -0.2794)
						)
					)
					(width 0)
					(fill yes)
				)
			)
		)
		(pad "2" smd custom
			(at 0 0.4445 270)
			(size 0.1397 0.1397)
			(layers "F.Cu" "F.Mask" "F.Paste")
			(net "P12VU_2490_RC")
			(options
				(clearance outline)
				(anchor circle)
			)
			(primitives
				(gr_poly
					(pts
						(arc
							(start -0.1778 -0.2794)
							(mid -0.249642 -0.249642)
							(end -0.2794 -0.1778)
						)
						(arc
							(start -0.2794 0.1778)
							(mid -0.249642 0.249642)
							(end -0.1778 0.2794)
						)
						(arc
							(start 0.1778 0.2794)
							(mid 0.249642 0.249642)
							(end 0.2794 0.1778)
						)
						(arc
							(start 0.2794 -0.1778)
							(mid 0.249642 -0.249642)
							(end 0.1778 -0.2794)
						)
					)
					(width 0)
					(fill yes)
				)
			)
		)
	)
	(footprint ""
		(layer "F.Cu")
		(at 14.8844 -39.4462 90)
		(property "Reference" "R120"
			(at 0 0 90)
			(layer "F.SilkS")
			(hide yes)
			(effects
				(font
					(size 1.27 1.27)
				)
			)
		)
		(property "Value" "470R2F-GP"
			(at 0.064008 -3.993896 90)
			(unlocked yes)
			(layer "F.Fab")
			(hide yes)
			(effects
				(font
					(size 1.016 1.016)
					(thickness 0.1524)
				)
			)
		)
		(property "Device Type" "R402H16"
			(at 0.064008 -5.517896 90)
			(unlocked yes)
			(layer "F.Fab")
			(hide yes)
			(effects
				(font
					(size 1.016 1.016)
					(thickness 0.1524)
				)
			)
		)
		(duplicate_pad_numbers_are_jumpers no)
		(fp_line
			(start 0.508 -0.9398)
			(end -0.508 -0.9398)
			(stroke
				(width 0.1524)
				(type default)
			)
			(layer "F.SilkS")
		)
		(fp_line
			(start -0.508 -0.9398)
			(end -0.508 0.9398)
			(stroke
				(width 0.1524)
				(type default)
			)
			(layer "F.SilkS")
		)
		(fp_rect
			(start -0.508 0.9398)
			(end 0.508 -0.9398)
			(stroke
				(width 0)
				(type default)
			)
			(fill no)
			(layer "F.CrtYd")
		)
		(fp_rect
			(start -0.508 0.9398)
			(end 0.508 -0.9398)
			(stroke
				(width 0)
				(type default)
			)
			(fill no)
			(layer "F.Fab")
		)
		(pad "1" smd custom
			(at 0 -0.4445 90)
			(size 0.1397 0.1397)
			(layers "F.Cu" "F.Mask" "F.Paste")
			(net "SEB_PEER_2B_HB")
			(options
				(clearance outline)
				(anchor circle)
			)
			(primitives
				(gr_poly
					(pts
						(arc
							(start -0.1778 -0.2794)
							(mid -0.249642 -0.249642)
							(end -0.2794 -0.1778)
						)
						(arc
							(start -0.2794 0.1778)
							(mid -0.249642 0.249642)
							(end -0.1778 0.2794)
						)
						(arc
							(start 0.1778 0.2794)
							(mid 0.249642 0.249642)
							(end 0.2794 0.1778)
						)
						(arc
							(start 0.2794 -0.1778)
							(mid 0.249642 -0.249642)
							(end 0.1778 -0.2794)
						)
					)
					(width 0)
					(fill yes)
				)
			)
		)
		(pad "2" smd custom
			(at 0 0.4445 90)
			(size 0.1397 0.1397)
			(layers "F.Cu" "F.Mask" "F.Paste")
			(net "GND")
			(options
				(clearance outline)
				(anchor circle)
			)
			(primitives
				(gr_poly
					(pts
						(arc
							(start -0.1778 -0.2794)
							(mid -0.249642 -0.249642)
							(end -0.2794 -0.1778)
						)
						(arc
							(start -0.2794 0.1778)
							(mid -0.249642 0.249642)
							(end -0.1778 0.2794)
						)
						(arc
							(start 0.1778 0.2794)
							(mid 0.249642 0.249642)
							(end 0.2794 0.1778)
						)
						(arc
							(start 0.2794 -0.1778)
							(mid 0.249642 -0.249642)
							(end 0.1778 -0.2794)
						)
					)
					(width 0)
					(fill yes)
				)
			)
		)
	)
	(footprint ""
		(layer "F.Cu")
		(at 22.537166 -135.554466 -90)
		(property "Reference" "PR98"
			(at 0 0 270)
			(layer "F.SilkS")
			(hide yes)
			(effects
				(font
					(size 1.27 1.27)
				)
			)
		)
		(property "Value" "1MR3J-L-GP"
			(at -0.0254 -2.5146 270)
			(unlocked yes)
			(layer "F.Fab")
			(hide yes)
			(effects
				(font
					(size 1.016 1.016)
					(thickness 0.1524)
				)
			)
		)
		(property "Device Type" "R603H22"
			(at -0.0254 -4.0386 270)
			(unlocked yes)
			(layer "F.Fab")
			(hide yes)
			(effects
				(font
					(size 1.016 1.016)
					(thickness 0.1524)
				)
			)
		)
		(duplicate_pad_numbers_are_jumpers no)
		(fp_line
			(start -0.4826 0)
			(end -0.2032 0)
			(stroke
				(width 0.2032)
				(type default)
			)
			(layer "F.SilkS")
		)
		(fp_line
			(start 0.2032 0)
			(end 0.4826 0)
			(stroke
				(width 0.2032)
				(type default)
			)
			(layer "F.SilkS")
		)
		(fp_rect
			(start -0.5842 1.3335)
			(end 0.5842 -1.3335)
			(stroke
				(width 0)
				(type default)
			)
			(fill no)
			(layer "F.CrtYd")
		)
		(fp_rect
			(start -0.5842 1.3335)
			(end 0.5842 -1.3335)
			(stroke
				(width 0)
				(type default)
			)
			(fill no)
			(layer "F.Fab")
		)
		(pad "1" smd custom
			(at 0 -0.762 270)
			(size 0.2159 0.2159)
			(layers "F.Cu" "F.Mask" "F.Paste")
			(net "P12VU_2490_VCC")
			(options
				(clearance outline)
				(anchor circle)
			)
			(primitives
				(gr_poly
					(pts
						(arc
							(start -0.3302 -0.4318)
							(mid -0.402042 -0.402042)
							(end -0.4318 -0.3302)
						)
						(arc
							(start -0.4318 0.3302)
							(mid -0.402042 0.402042)
							(end -0.3302 0.4318)
						)
						(arc
							(start 0.3302 0.4318)
							(mid 0.402042 0.402042)
							(end 0.4318 0.3302)
						)
						(arc
							(start 0.4318 -0.3302)
							(mid 0.402042 -0.402042)
							(end 0.3302 -0.4318)
						)
					)
					(width 0)
					(fill yes)
				)
			)
		)
		(pad "2" smd custom
			(at 0 0.762 270)
			(size 0.2159 0.2159)
			(layers "F.Cu" "F.Mask" "F.Paste")
			(net "P12VU_2490_SENSE")
			(options
				(clearance outline)
				(anchor circle)
			)
			(primitives
				(gr_poly
					(pts
						(arc
							(start -0.3302 -0.4318)
							(mid -0.402042 -0.402042)
							(end -0.4318 -0.3302)
						)
						(arc
							(start -0.4318 0.3302)
							(mid -0.402042 0.402042)
							(end -0.3302 0.4318)
						)
						(arc
							(start 0.3302 0.4318)
							(mid 0.402042 0.402042)
							(end 0.4318 0.3302)
						)
						(arc
							(start 0.4318 -0.3302)
							(mid 0.402042 -0.402042)
							(end 0.3302 -0.4318)
						)
					)
					(width 0)
					(fill yes)
				)
			)
		)
	)
	(footprint ""
		(layer "F.Cu")
		(at 45.500036 -480.000056)
		(property "Reference" "H3"
			(at 0 0 0)
			(layer "F.SilkS")
			(hide yes)
			(effects
				(font
					(size 1.27 1.27)
				)
			)
		)
		(property "Value" "HOLE315R158"
			(at -5.08 -0.4572 0)
			(unlocked yes)
			(layer "F.Fab")
			(hide yes)
			(effects
				(font
					(size 1.016 1.016)
					(thickness 0.1524)
				)
			)
		)
		(property "Device Type" "HOLE315R158"
			(at -5.08 -1.9812 0)
			(unlocked yes)
			(layer "F.Fab")
			(hide yes)
			(effects
				(font
					(size 1.016 1.016)
					(thickness 0.1524)
				)
			)
		)
		(duplicate_pad_numbers_are_jumpers no)
		(fp_poly
			(pts
				(arc
					(start -4.3053 0)
					(mid 4.3053 0)
					(end -4.3053 0)
				)
			)
			(stroke
				(width 0)
				(type default)
			)
			(fill no)
			(layer "B.CrtYd")
		)
		(fp_poly
			(pts
				(arc
					(start -4.3053 0)
					(mid 4.3053 0)
					(end -4.3053 0)
				)
			)
			(stroke
				(width 0)
				(type default)
			)
			(fill no)
			(layer "F.CrtYd")
		)
		(fp_poly
			(pts
				(arc
					(start -4.3053 0)
					(mid 4.3053 0)
					(end -4.3053 0)
				)
			)
			(stroke
				(width 0)
				(type default)
			)
			(fill no)
			(layer "B.Fab")
		)
		(fp_poly
			(pts
				(arc
					(start -4.3053 0)
					(mid 4.3053 0)
					(end -4.3053 0)
				)
			)
			(stroke
				(width 0)
				(type default)
			)
			(fill no)
			(layer "F.Fab")
		)
		(pad "1" thru_hole circle
			(at 0 0)
			(size 8.001 8.001)
			(drill 4.0132)
			(layers "*.Cu" "*.Mask")
			(remove_unused_layers no)
			(net "GND")
			(clearance -1.4859)
			(thermal_gap 0.3048)
			(padstack
				(mode front_inner_back)
				(layer "Inner"
					(shape circle)
					(size 4.4196 4.4196)
					(clearance 0.3048)
				)
				(layer "B.Cu"
					(shape circle)
					(size 8.001 8.001)
					(clearance -1.4859)
				)
			)
		)
	)
	(footprint ""
		(layer "F.Cu")
		(at 7.949946 -267.865098 -90)
		(property "Reference" "LED3"
			(at 0 0 270)
			(layer "F.SilkS")
			(hide yes)
			(effects
				(font
					(size 1.27 1.27)
				)
			)
		)
		(property "Value" "LED-RB-6-GP"
			(at -4.6736 3.8354 270)
			(unlocked yes)
			(layer "F.Fab")
			(hide yes)
			(effects
				(font
					(size 1.016 1.016)
					(thickness 0.1524)
				)
			)
		)
		(property "Device Type" "LED-100-3P-067106H325"
			(at -4.6736 2.3114 270)
			(unlocked yes)
			(layer "F.Fab")
			(hide yes)
			(effects
				(font
					(size 1.016 1.016)
					(thickness 0.1524)
				)
			)
		)
		(duplicate_pad_numbers_are_jumpers no)
		(fp_line
			(start -1.7526 10.414)
			(end -1.7526 6.6548)
			(stroke
				(width 0.1524)
				(type default)
			)
			(layer "F.SilkS")
		)
		(fp_line
			(start 1.7526 10.414)
			(end -1.7526 10.414)
			(stroke
				(width 0.1524)
				(type default)
			)
			(layer "F.SilkS")
		)
		(fp_line
			(start -3.6068 6.6548)
			(end -3.6068 -0.889)
			(stroke
				(width 0.1524)
				(type default)
			)
			(layer "F.SilkS")
		)
		(fp_line
			(start -1.7526 6.6548)
			(end -3.6068 6.6548)
			(stroke
				(width 0.1524)
				(type default)
			)
			(layer "F.SilkS")
		)
		(fp_line
			(start 1.7526 6.6548)
			(end 1.7526 10.414)
			(stroke
				(width 0.1524)
				(type default)
			)
			(layer "F.SilkS")
		)
		(fp_line
			(start 3.6068 6.6548)
			(end 1.7526 6.6548)
			(stroke
				(width 0.1524)
				(type default)
			)
			(layer "F.SilkS")
		)
		(fp_line
			(start -3.6068 -0.889)
			(end 3.6068 -0.889)
			(stroke
				(width 0.1524)
				(type default)
			)
			(layer "F.SilkS")
		)
		(fp_line
			(start 3.6068 -0.889)
			(end 3.6068 6.6548)
			(stroke
				(width 0.1524)
				(type default)
			)
			(layer "F.SilkS")
		)
		(fp_circle
			(center -2.54 0)
			(end -2.54 -0.9906)
			(stroke
				(width 0.3048)
				(type default)
			)
			(fill no)
			(layer "F.SilkS")
		)
		(fp_circle
			(center 0 0)
			(end 0 -0.9906)
			(stroke
				(width 0.3048)
				(type default)
			)
			(fill no)
			(layer "F.SilkS")
		)
		(fp_circle
			(center 2.54 0)
			(end 2.54 -0.9906)
			(stroke
				(width 0.3048)
				(type default)
			)
			(fill no)
			(layer "F.SilkS")
		)
		(fp_poly
			(pts
				(xy -1.4986 10.1473) (xy -1.4986 6.4008) (xy -3.3528 6.4008) (xy -3.3528 -0.3937) (xy 3.3528 -0.3937)
				(xy 3.3528 6.4008) (xy 1.4986 6.4008) (xy 1.4986 10.1473)
			)
			(stroke
				(width 0)
				(type default)
			)
			(fill no)
			(layer "F.CrtYd")
		)
		(fp_poly
			(pts
				(xy -2.0066 10.668) (xy 2.0066 10.668) (xy 2.0066 6.9088) (xy 3.8608 6.9088) (xy 3.8608 2.2098)
				(xy 3.3528 2.2098) (xy 3.3528 6.4008) (xy 1.4986 6.4008) (xy 1.4986 10.1473) (xy -1.4986 10.1473)
				(xy -1.4986 6.4008) (xy -3.3528 6.4008) (xy -3.3528 -0.3937) (xy 3.3528 -0.3937) (xy 3.3528 2.1971)
				(xy 3.8608 2.1971) (xy 3.8608 -1.143) (xy -3.8608 -1.143) (xy -3.8608 6.9088) (xy -2.0066 6.9088)
			)
			(stroke
				(width 0)
				(type default)
			)
			(fill no)
			(layer "F.CrtYd")
		)
		(fp_poly
			(pts
				(xy -2.0066 10.668) (xy -2.0066 6.9088) (xy -3.8608 6.9088) (xy -3.8608 -1.143) (xy 3.8608 -1.143)
				(xy 3.8608 6.9088) (xy 2.0066 6.9088) (xy 2.0066 10.668)
			)
			(stroke
				(width 0)
				(type default)
			)
			(fill no)
			(layer "F.Fab")
		)
		(pad "1" thru_hole circle
			(at 2.54 0 270)
			(size 1.27 1.27)
			(drill 0.889)
			(layers "*.Cu" "*.Mask")
			(remove_unused_layers no)
			(net "LED_DR_LED2_BLUE")
			(clearance 0.1651)
			(thermal_gap 0.1651)
		)
		(pad "2" thru_hole circle
			(at 0 0 270)
			(size 1.27 1.27)
			(drill 0.889)
			(layers "*.Cu" "*.Mask")
			(remove_unused_layers no)
			(net "LED_DR_LED2_K")
			(clearance 0.1651)
			(thermal_gap 0.1651)
		)
		(pad "3" thru_hole circle
			(at -2.54 0 270)
			(size 1.27 1.27)
			(drill 0.889)
			(layers "*.Cu" "*.Mask")
			(remove_unused_layers no)
			(net "LED_DR_LED2")
			(clearance 0.1651)
			(thermal_gap 0.1651)
		)
	)
	(footprint ""
		(layer "F.Cu")
		(at 21.6916 -144.7546 -90)
		(property "Reference" "PR110"
			(at 0 0 270)
			(layer "F.SilkS")
			(hide yes)
			(effects
				(font
					(size 1.27 1.27)
				)
			)
		)
		(property "Value" "178KR2F-GP"
			(at 0.064008 -3.993896 270)
			(unlocked yes)
			(layer "F.Fab")
			(hide yes)
			(effects
				(font
					(size 1.016 1.016)
					(thickness 0.1524)
				)
			)
		)
		(property "Device Type" "R402H16"
			(at 0.064008 -5.517896 270)
			(unlocked yes)
			(layer "F.Fab")
			(hide yes)
			(effects
				(font
					(size 1.016 1.016)
					(thickness 0.1524)
				)
			)
		)
		(duplicate_pad_numbers_are_jumpers no)
		(fp_line
			(start -0.508 -0.9398)
			(end -0.508 0.9398)
			(stroke
				(width 0.1524)
				(type default)
			)
			(layer "F.SilkS")
		)
		(fp_line
			(start 0.508 -0.9398)
			(end -0.508 -0.9398)
			(stroke
				(width 0.1524)
				(type default)
			)
			(layer "F.SilkS")
		)
		(fp_rect
			(start -0.508 0.9398)
			(end 0.508 -0.9398)
			(stroke
				(width 0)
				(type default)
			)
			(fill no)
			(layer "F.CrtYd")
		)
		(fp_rect
			(start -0.508 0.9398)
			(end 0.508 -0.9398)
			(stroke
				(width 0)
				(type default)
			)
			(fill no)
			(layer "F.Fab")
		)
		(pad "1" smd custom
			(at 0 -0.4445 270)
			(size 0.1397 0.1397)
			(layers "F.Cu" "F.Mask" "F.Paste")
			(net "P12VU_2490_VREF")
			(options
				(clearance outline)
				(anchor circle)
			)
			(primitives
				(gr_poly
					(pts
						(arc
							(start -0.1778 -0.2794)
							(mid -0.249642 -0.249642)
							(end -0.2794 -0.1778)
						)
						(arc
							(start -0.2794 0.1778)
							(mid -0.249642 0.249642)
							(end -0.1778 0.2794)
						)
						(arc
							(start 0.1778 0.2794)
							(mid 0.249642 0.249642)
							(end 0.2794 0.1778)
						)
						(arc
							(start 0.2794 -0.1778)
							(mid 0.249642 -0.249642)
							(end 0.1778 -0.2794)
						)
					)
					(width 0)
					(fill yes)
				)
			)
		)
		(pad "2" smd custom
			(at 0 0.4445 270)
			(size 0.1397 0.1397)
			(layers "F.Cu" "F.Mask" "F.Paste")
			(net "P12VU_2490_PROG")
			(options
				(clearance outline)
				(anchor circle)
			)
			(primitives
				(gr_poly
					(pts
						(arc
							(start -0.1778 -0.2794)
							(mid -0.249642 -0.249642)
							(end -0.2794 -0.1778)
						)
						(arc
							(start -0.2794 0.1778)
							(mid -0.249642 0.249642)
							(end -0.1778 0.2794)
						)
						(arc
							(start 0.1778 0.2794)
							(mid 0.249642 0.249642)
							(end 0.2794 0.1778)
						)
						(arc
							(start 0.2794 -0.1778)
							(mid 0.249642 -0.249642)
							(end 0.1778 -0.2794)
						)
					)
					(width 0)
					(fill yes)
				)
			)
		)
	)
	(footprint ""
		(layer "F.Cu")
		(at 23.622 -170.434 -90)
		(property "Reference" "R21"
			(at 0 0 270)
			(layer "F.SilkS")
			(hide yes)
			(effects
				(font
					(size 1.27 1.27)
				)
			)
		)
		(property "Value" "100KR2F-L1-GP"
			(at 0.064008 -3.993896 270)
			(unlocked yes)
			(layer "F.Fab")
			(hide yes)
			(effects
				(font
					(size 1.016 1.016)
					(thickness 0.1524)
				)
			)
		)
		(property "Device Type" "R402H16"
			(at 0.064008 -5.517896 270)
			(unlocked yes)
			(layer "F.Fab")
			(hide yes)
			(effects
				(font
					(size 1.016 1.016)
					(thickness 0.1524)
				)
			)
		)
		(duplicate_pad_numbers_are_jumpers no)
		(fp_line
			(start -0.508 -0.9398)
			(end -0.508 0.9398)
			(stroke
				(width 0.1524)
				(type default)
			)
			(layer "F.SilkS")
		)
		(fp_line
			(start 0.508 -0.9398)
			(end -0.508 -0.9398)
			(stroke
				(width 0.1524)
				(type default)
			)
			(layer "F.SilkS")
		)
		(fp_rect
			(start -0.508 0.9398)
			(end 0.508 -0.9398)
			(stroke
				(width 0)
				(type default)
			)
			(fill no)
			(layer "F.CrtYd")
		)
		(fp_rect
			(start -0.508 0.9398)
			(end 0.508 -0.9398)
			(stroke
				(width 0)
				(type default)
			)
			(fill no)
			(layer "F.Fab")
		)
		(pad "1" smd custom
			(at 0 -0.4445 270)
			(size 0.1397 0.1397)
			(layers "F.Cu" "F.Mask" "F.Paste")
			(net "PWM_EXP_2B")
			(options
				(clearance outline)
				(anchor circle)
			)
			(primitives
				(gr_poly
					(pts
						(arc
							(start -0.1778 -0.2794)
							(mid -0.249642 -0.249642)
							(end -0.2794 -0.1778)
						)
						(arc
							(start -0.2794 0.1778)
							(mid -0.249642 0.249642)
							(end -0.1778 0.2794)
						)
						(arc
							(start 0.1778 0.2794)
							(mid 0.249642 0.249642)
							(end 0.2794 0.1778)
						)
						(arc
							(start 0.2794 -0.1778)
							(mid 0.249642 -0.249642)
							(end 0.1778 -0.2794)
						)
					)
					(width 0)
					(fill yes)
				)
			)
		)
		(pad "2" smd custom
			(at 0 0.4445 270)
			(size 0.1397 0.1397)
			(layers "F.Cu" "F.Mask" "F.Paste")
			(net "GND")
			(options
				(clearance outline)
				(anchor circle)
			)
			(primitives
				(gr_poly
					(pts
						(arc
							(start -0.1778 -0.2794)
							(mid -0.249642 -0.249642)
							(end -0.2794 -0.1778)
						)
						(arc
							(start -0.2794 0.1778)
							(mid -0.249642 0.249642)
							(end -0.1778 0.2794)
						)
						(arc
							(start 0.1778 0.2794)
							(mid 0.249642 0.249642)
							(end 0.2794 0.1778)
						)
						(arc
							(start 0.2794 -0.1778)
							(mid 0.249642 -0.249642)
							(end 0.1778 -0.2794)
						)
					)
					(width 0)
					(fill yes)
				)
			)
		)
	)
)
